# S9S_MB_2U (Grand Teton) — schematic netlist excerpt (pin names and nets, part order shuffled) for the footprints in the layout excerpt that follows; sources: Cadence DE-HDL packaged netlist, KiCad conversion of 03242023_DA0F0TMBIJ0_F0T_Motherboard_J_brd_V01_OCP.brd

H114  GND_HOLE  EMPTY  pkg TH  page 311
  GND2  = GND
  GND3  = GND
  GND4  = GND
  GND5  = GND
  GND6  = GND
  GND7  = GND
  GND8  = GND
  GND9  = GND

C758  Q_CAP_DIFFBUS  DIFF BUS_0.22UF 6.3V 20% X6S  pkg C0201  page 176 : \1\ = P5E_CPU1_PE2_TX_C_DN<7> ; \2\ = P5E_CPU1_PE2_TX_DN<7>

(kicad_pcb
	(version 20260206)
	(generator "pcbnew")
	(generator_version "10.0")
	(general
		(thickness 1.6)
		(legacy_teardrops no)
	)
	(paper "A4")
	(title_block
		(title "03242023_DA0F0TMBIJ0_F0T_Motherboard_J_brd_V01_OCP.brd")
		(comment 1 "Grand Teton / footprints 2349-2350 of 6105")
	)
	(layers
		(0 "F.Cu" signal "TOP")
		(4 "In1.Cu" signal "GND")
		(6 "In2.Cu" signal "IN1")
		(8 "In3.Cu" signal "GND1")
		(10 "In4.Cu" signal "IN2")
		(12 "In5.Cu" signal "GND2")
		(14 "In6.Cu" signal "IN3")
		(16 "In7.Cu" signal "GND3")
		(18 "In8.Cu" signal "VCC")
		(20 "In9.Cu" signal "VCC1")
		(22 "In10.Cu" signal "GND4")
		(24 "In11.Cu" signal "IN4")
		(26 "In12.Cu" signal "GND5")
		(28 "In13.Cu" signal "IN5")
		(30 "In14.Cu" signal "GND6")
		(32 "In15.Cu" signal "IN6")
		(34 "In16.Cu" signal "GND7")
		(2 "B.Cu" signal "BOTTOM")
		(9 "F.Adhes" user "F.Adhesive")
		(11 "B.Adhes" user "B.Adhesive")
		(13 "F.Paste" user "Package Geometry/Pastemask Top")
		(15 "B.Paste" user "Package Geometry/Pastemask Bottom")
		(5 "F.SilkS" user "Ref Des/Silkscreen Top")
		(7 "B.SilkS" user "Ref Des/Silkscreen Bottom")
		(1 "F.Mask" user "Board Geometry/Soldermask Top")
		(3 "B.Mask" user "Board Geometry/Soldermask Bottom")
		(17 "Dwgs.User" user "User.Drawings")
		(19 "Cmts.User" user "User.Comments")
		(21 "Eco1.User" user "User.Eco1")
		(23 "Eco2.User" user "User.Eco2")
		(25 "Edge.Cuts" user "Board Geometry/Outline")
		(27 "Margin" user)
		(31 "F.CrtYd" user "Package Geometry/Place Bound Top")
		(29 "B.CrtYd" user "Package Geometry/Place Bound Bottom")
		(35 "F.Fab" user "Ref Des/Assembly Top")
		(33 "B.Fab" user "Ref Des/Assembly Bottom")
	)
	(footprint ""
		(layer "F.Cu")
		(at 213.67496 -360.76382)
		(property "Reference" "H114"
			(at -6.1087 -8.006588 0)
			(unlocked yes)
			(layer "F.SilkS")
			(effects
				(font
					(size 0.7874 0.5842)
					(thickness 0.1524)
				)
				(justify left)
			)
		)
		(property "Value" ""
			(at 0 0 0)
			(layer "F.Fab")
			(effects
				(font
					(size 1.27 1.27)
				)
			)
		)
		(duplicate_pad_numbers_are_jumpers no)
		(fp_circle
			(center 0 0)
			(end 7.999984 0)
			(stroke
				(width 0.1524)
				(type default)
			)
			(fill no)
			(layer "F.SilkS")
		)
		(fp_circle
			(center 0 0)
			(end 7.999984 0)
			(stroke
				(width 0.1524)
				(type default)
			)
			(fill no)
			(layer "B.SilkS")
		)
		(fp_circle
			(center 0 0)
			(end 7.999984 0)
			(stroke
				(width 0.1)
				(type default)
			)
			(fill no)
			(layer "B.Fab")
		)
		(fp_circle
			(center 0 0)
			(end 7.999984 0)
			(stroke
				(width 0.1)
				(type default)
			)
			(fill no)
			(layer "F.Fab")
		)
		(pad "" np_thru_hole circle
			(at 0 0)
			(size 4.0132 4.0132)
			(drill 4.0132)
			(layers "*.Cu" "*.Mask")
			(clearance 0.381)
			(thermal_gap 0.381)
		)
		(pad "2" thru_hole circle
			(at 3.2639 0)
			(size 0.9144 0.9144)
			(drill 0.5588)
			(layers "*.Cu" "*.Mask")
			(remove_unused_layers no)
			(net "GND")
			(clearance 0.0762)
			(thermal_gap 0.0762)
		)
		(pad "3" thru_hole circle
			(at 2.307844 -2.307844)
			(size 0.9144 0.9144)
			(drill 0.5588)
			(layers "*.Cu" "*.Mask")
			(remove_unused_layers no)
			(net "GND")
			(clearance 0.0762)
			(thermal_gap 0.0762)
		)
		(pad "4" thru_hole circle
			(at 0 -3.2639)
			(size 0.9144 0.9144)
			(drill 0.5588)
			(layers "*.Cu" "*.Mask")
			(remove_unused_layers no)
			(net "GND")
			(clearance 0.0762)
			(thermal_gap 0.0762)
		)
		(pad "5" thru_hole circle
			(at -2.307844 -2.307844)
			(size 0.9144 0.9144)
			(drill 0.5588)
			(layers "*.Cu" "*.Mask")
			(remove_unused_layers no)
			(net "GND")
			(clearance 0.0762)
			(thermal_gap 0.0762)
		)
		(pad "6" thru_hole circle
			(at -3.2639 0)
			(size 0.9144 0.9144)
			(drill 0.5588)
			(layers "*.Cu" "*.Mask")
			(remove_unused_layers no)
			(net "GND")
			(clearance 0.0762)
			(thermal_gap 0.0762)
		)
		(pad "7" thru_hole circle
			(at -2.307844 2.307844)
			(size 0.9144 0.9144)
			(drill 0.5588)
			(layers "*.Cu" "*.Mask")
			(remove_unused_layers no)
			(net "GND")
			(clearance 0.0762)
			(thermal_gap 0.0762)
		)
		(pad "8" thru_hole circle
			(at 0 3.2639)
			(size 0.9144 0.9144)
			(drill 0.5588)
			(layers "*.Cu" "*.Mask")
			(remove_unused_layers no)
			(net "GND")
			(clearance 0.0762)
			(thermal_gap 0.0762)
		)
		(pad "9" thru_hole circle
			(at 2.307844 2.307844)
			(size 0.9144 0.9144)
			(drill 0.5588)
			(layers "*.Cu" "*.Mask")
			(remove_unused_layers no)
			(net "GND")
			(clearance 0.0762)
			(thermal_gap 0.0762)
		)
		(zone
			(layer "F.Cu")
			(hatch none 0.5)
			(connect_pads
				(clearance 0)
			)
			(min_thickness 0.25)
			(keepout
				(tracks not_allowed)
				(vias allowed)
				(pads allowed)
				(copperpour not_allowed)
				(footprints allowed)
			)
			(placement
				(enabled no)
				(sheetname "")
			)
			(fill
				(thermal_gap 0.5)
				(thermal_bridge_width 0.5)
				(island_removal_mode 0)
			)
			(polygon
				(pts
					(arc
						(start 213.67496 -356.49662)
						(mid 209.40776 -360.76382)
						(end 213.67496 -365.03102)
					)
					(arc
						(start 213.67496 -368.763804)
						(mid 208.018117 -366.420663)
						(end 205.674976 -360.76382)
					)
					(arc
						(start 205.674976 -360.76382)
						(mid 208.018117 -355.106977)
						(end 213.67496 -352.763836)
					)
				)
			)
		)
		(zone
			(layer "F.Cu")
			(hatch none 0.5)
			(connect_pads
				(clearance 0)
			)
			(min_thickness 0.25)
			(keepout
				(tracks not_allowed)
				(vias allowed)
				(pads allowed)
				(copperpour not_allowed)
				(footprints allowed)
			)
			(placement
				(enabled no)
				(sheetname "")
			)
			(fill
				(thermal_gap 0.5)
				(thermal_bridge_width 0.5)
				(island_removal_mode 0)
			)
			(polygon
				(pts
					(arc
						(start 213.67496 -356.49662)
						(mid 217.94216 -360.76382)
						(end 213.67496 -365.03102)
					)
					(arc
						(start 213.67496 -368.763804)
						(mid 219.331803 -366.420663)
						(end 221.674944 -360.76382)
					)
					(arc
						(start 221.674944 -360.76382)
						(mid 219.331803 -355.106977)
						(end 213.67496 -352.763836)
					)
				)
			)
		)
		(zone
			(layers "F.Cu" "B.Cu" "In1.Cu" "In2.Cu" "In3.Cu" "In4.Cu" "In5.Cu" "In6.Cu"
				"In7.Cu" "In8.Cu" "In9.Cu" "In10.Cu" "In11.Cu" "In12.Cu" "In13.Cu" "In14.Cu"
				"In15.Cu" "In16.Cu"
			)
			(hatch none 0.5)
			(connect_pads
				(clearance 0)
			)
			(min_thickness 0.25)
			(keepout
				(tracks not_allowed)
				(vias allowed)
				(pads allowed)
				(copperpour not_allowed)
				(footprints allowed)
			)
			(placement
				(enabled no)
				(sheetname "")
			)
			(fill
				(thermal_gap 0.5)
				(thermal_bridge_width 0.5)
				(island_removal_mode 0)
			)
			(polygon
				(pts
					(arc
						(start 216.18702 -360.76382)
						(mid 211.1629 -360.76382)
						(end 216.18702 -360.76382)
					)
				)
			)
		)
		(zone
			(layer "B.Cu")
			(hatch none 0.5)
			(connect_pads
				(clearance 0)
			)
			(min_thickness 0.25)
			(keepout
				(tracks not_allowed)
				(vias allowed)
				(pads allowed)
				(copperpour not_allowed)
				(footprints allowed)
			)
			(placement
				(enabled no)
				(sheetname "")
			)
			(fill
				(thermal_gap 0.5)
				(thermal_bridge_width 0.5)
				(island_removal_mode 0)
			)
			(polygon
				(pts
					(arc
						(start 213.67496 -365.28502)
						(mid 209.15376 -360.76382)
						(end 213.67496 -356.24262)
					)
					(arc
						(start 213.67496 -356.72522)
						(mid 209.63636 -360.76382)
						(end 213.67496 -364.80242)
					)
				)
			)
		)
		(zone
			(layer "B.Cu")
			(hatch none 0.5)
			(connect_pads
				(clearance 0)
			)
			(min_thickness 0.25)
			(keepout
				(tracks not_allowed)
				(vias allowed)
				(pads allowed)
				(copperpour not_allowed)
				(footprints allowed)
			)
			(placement
				(enabled no)
				(sheetname "")
			)
			(fill
				(thermal_gap 0.5)
				(thermal_bridge_width 0.5)
				(island_removal_mode 0)
			)
			(polygon
				(pts
					(arc
						(start 213.67496 -365.28502)
						(mid 218.19616 -360.76382)
						(end 213.67496 -356.24262)
					)
					(arc
						(start 213.67496 -356.72522)
						(mid 217.71356 -360.76382)
						(end 213.67496 -364.80242)
					)
				)
			)
		)
	)
	(footprint ""
		(layer "F.Cu")
		(at 145.549874 -402.371052 -90)
		(property "Reference" "C758"
			(at 0 0 270)
			(layer "F.SilkS")
			(hide yes)
			(effects
				(font
					(size 1.27 1.27)
				)
			)
		)
		(property "Value" ""
			(at 0 0 270)
			(layer "F.Fab")
			(effects
				(font
					(size 1.27 1.27)
				)
			)
		)
		(duplicate_pad_numbers_are_jumpers no)
		(fp_line
			(start -0.299974 0.150114)
			(end -0.299974 -0.150114)
			(stroke
				(width 0.1)
				(type default)
			)
			(layer "F.Fab")
		)
		(fp_line
			(start 0.299974 0.150114)
			(end -0.299974 0.150114)
			(stroke
				(width 0.1)
				(type default)
			)
			(layer "F.Fab")
		)
		(fp_line
			(start -0.299974 -0.150114)
			(end 0.299974 -0.150114)
			(stroke
				(width 0.1)
				(type default)
			)
			(layer "F.Fab")
		)
		(fp_line
			(start 0.299974 -0.150114)
			(end 0.299974 0.150114)
			(stroke
				(width 0.1)
				(type default)
			)
			(layer "F.Fab")
		)
		(pad "1" smd rect
			(at -0.2667 0 270)
			(size 0.3048 0.381)
			(layers "F.Cu" "F.Mask" "F.Paste")
			(net "P5E_CPU1_PE2_TX_C_DN<7>")
		)
		(pad "2" smd rect
			(at 0.2667 0 270)
			(size 0.3048 0.381)
			(layers "F.Cu" "F.Mask" "F.Paste")
			(net "P5E_CPU1_PE2_TX_DN<7>")
		)
	)
)
